FILE_TYPE = CONNECTIVITY;
{Allegro Design Entry HDL 17.2-2016 S081 (4005846) 1/11/2022}
"PAGE_NUMBER" = 189;
0"NC";
END.
